# T6G (Grand Teton) — schematic netlist excerpt (pin names and nets, part order shuffled) for the footprints in the layout excerpt that follows; sources: Cadence DE-HDL packaged netlist, KiCad conversion of 04192023_DAF0TMB3IC0_F0TG_MB_C_brd_V02_OCP.brd

PL41  Q_INDUCTOR4P_14  150NH IND  pkg L_TLM117513Q-151QL_11X7-5XA  page 218
  \1\  = SW_PVDDCR_CPU1_P1_SW2
  \2\  = IND_CPU1_P1_CPL1
  \3\  = IND_CPU1_P1_CPL2
  \4\  = PVDDCR_CPU1_P1

U259  SN74LVC2G07DCKR  IC  pkg SMLF  page 144
  \1a\  = M2_SSD0_CLKREQ_EN_N
  GND  = GND
  \2a\  = RST_PERST_M2_0_N
  \2y\  = RST_PERST_BUF_M2_0_N
  VCC  = P3V3_AUX
  \1y\  = HDD_ACTIVITY_BUF

(kicad_pcb
	(version 20260206)
	(generator "pcbnew")
	(generator_version "10.0")
	(general
		(thickness 1.6)
		(legacy_teardrops no)
	)
	(paper "A4")
	(title_block
		(title "04192023_DAF0TMB3IC0_F0TG_MB_C_brd_V02_OCP.brd")
		(comment 1 "Grand Teton / footprints 1867-1868 of 8354")
	)
	(layers
		(0 "F.Cu" signal "TOP")
		(4 "In1.Cu" signal "GND")
		(6 "In2.Cu" signal "IN1")
		(8 "In3.Cu" signal "GND1")
		(10 "In4.Cu" signal "IN2")
		(12 "In5.Cu" signal "GND2")
		(14 "In6.Cu" signal "IN3")
		(16 "In7.Cu" signal "GND3")
		(18 "In8.Cu" signal "VCC")
		(20 "In9.Cu" signal "VCC1")
		(22 "In10.Cu" signal "GND4")
		(24 "In11.Cu" signal "IN4")
		(26 "In12.Cu" signal "GND5")
		(28 "In13.Cu" signal "IN5")
		(30 "In14.Cu" signal "GND6")
		(32 "In15.Cu" signal "IN6")
		(34 "In16.Cu" signal "GND7")
		(2 "B.Cu" signal "BOTTOM")
		(9 "F.Adhes" user "F.Adhesive")
		(11 "B.Adhes" user "B.Adhesive")
		(13 "F.Paste" user "Package Geometry/Pastemask Top")
		(15 "B.Paste" user "Package Geometry/Pastemask Bottom")
		(5 "F.SilkS" user "Ref Des/Silkscreen Top")
		(7 "B.SilkS" user "Ref Des/Silkscreen Bottom")
		(1 "F.Mask" user "Board Geometry/Soldermask Top")
		(3 "B.Mask" user "Board Geometry/Soldermask Bottom")
		(17 "Dwgs.User" user "User.Drawings")
		(19 "Cmts.User" user "User.Comments")
		(21 "Eco1.User" user "User.Eco1")
		(23 "Eco2.User" user "User.Eco2")
		(25 "Edge.Cuts" user "Board Geometry/Outline")
		(27 "Margin" user)
		(31 "F.CrtYd" user "Package Geometry/Place Bound Top")
		(29 "B.CrtYd" user "Package Geometry/Place Bound Bottom")
		(35 "F.Fab" user "Ref Des/Assembly Top")
		(33 "B.Fab" user "Ref Des/Assembly Bottom")
	)
	(footprint ""
		(layer "F.Cu")
		(at 144.74063 -101.894132)
		(property "Reference" "U259"
			(at 2.9464 -1.69037 0)
			(unlocked yes)
			(layer "F.SilkS")
			(effects
				(font
					(size 0.7874 0.5842)
					(thickness 0.1524)
				)
			)
		)
		(property "Value" ""
			(at 0 0 0)
			(layer "F.Fab")
			(effects
				(font
					(size 1.27 1.27)
				)
			)
		)
		(duplicate_pad_numbers_are_jumpers no)
		(fp_line
			(start -1.7272 1.1176)
			(end -1.7272 -1.1176)
			(stroke
				(width 0.1524)
				(type default)
			)
			(layer "F.SilkS")
		)
		(fp_line
			(start -0.254 -1.1176)
			(end -1.7272 -1.1176)
			(stroke
				(width 0.1524)
				(type default)
			)
			(layer "F.SilkS")
		)
		(fp_line
			(start 0 -0.7366)
			(end -0.254 -1.1176)
			(stroke
				(width 0.1524)
				(type default)
			)
			(layer "F.SilkS")
		)
		(fp_line
			(start 0.254 -1.1176)
			(end 0 -0.7366)
			(stroke
				(width 0.1524)
				(type default)
			)
			(layer "F.SilkS")
		)
		(fp_line
			(start 1.7272 -1.1176)
			(end 0.254 -1.1176)
			(stroke
				(width 0.1524)
				(type default)
			)
			(layer "F.SilkS")
		)
		(fp_line
			(start 1.7272 -1.1176)
			(end 1.7272 1.1176)
			(stroke
				(width 0.1524)
				(type default)
			)
			(layer "F.SilkS")
		)
		(fp_line
			(start 1.7272 1.1176)
			(end -1.7272 1.1176)
			(stroke
				(width 0.1524)
				(type default)
			)
			(layer "F.SilkS")
		)
		(fp_poly
			(pts
				(xy -2.7178 -1.030986) (xy -1.9558 -0.649986) (xy -2.7178 -0.268986)
			)
			(stroke
				(width 0)
				(type default)
			)
			(fill yes)
			(layer "F.SilkS")
		)
		(fp_line
			(start -1.5748 -1.1176)
			(end -1.5748 1.1176)
			(stroke
				(width 0.1)
				(type default)
			)
			(layer "F.Fab")
		)
		(fp_line
			(start -1.5748 1.1176)
			(end 1.5748 1.1176)
			(stroke
				(width 0.1)
				(type default)
			)
			(layer "F.Fab")
		)
		(fp_line
			(start 1.5748 -1.1176)
			(end -1.5748 -1.1176)
			(stroke
				(width 0.1)
				(type default)
			)
			(layer "F.Fab")
		)
		(fp_line
			(start 1.5748 1.1176)
			(end 1.5748 -1.1176)
			(stroke
				(width 0.1)
				(type default)
			)
			(layer "F.Fab")
		)
		(fp_poly
			(pts
				(xy -1.9558 -0.649986) (xy -2.7178 -0.268986) (xy -2.7178 -1.030986)
			)
			(stroke
				(width 0)
				(type default)
			)
			(fill yes)
			(layer "F.Fab")
		)
		(pad "1" smd rect
			(at -0.999998 -0.649986 270)
			(size 0.3556 1.1176)
			(layers "F.Cu" "F.Mask" "F.Paste")
			(net "M2_SSD0_CLKREQ_EN_N")
		)
		(pad "2" smd rect
			(at -0.999998 0 270)
			(size 0.3556 1.1176)
			(layers "F.Cu" "F.Mask" "F.Paste")
			(net "GND")
		)
		(pad "3" smd rect
			(at -0.999998 0.649986 270)
			(size 0.3556 1.1176)
			(layers "F.Cu" "F.Mask" "F.Paste")
			(net "RST_PERST_M2_0_N")
		)
		(pad "4" smd rect
			(at 0.999998 0.649986 270)
			(size 0.3556 1.1176)
			(layers "F.Cu" "F.Mask" "F.Paste")
			(net "RST_PERST_BUF_M2_0_N")
		)
		(pad "5" smd rect
			(at 0.999998 0 270)
			(size 0.3556 1.1176)
			(layers "F.Cu" "F.Mask" "F.Paste")
			(net "P3V3_AUX")
		)
		(pad "6" smd rect
			(at 0.999998 -0.649986 270)
			(size 0.3556 1.1176)
			(layers "F.Cu" "F.Mask" "F.Paste")
			(net "HDD_ACTIVITY_BUF")
		)
	)
	(footprint ""
		(layer "F.Cu")
		(at 78.882494 -325.661274)
		(property "Reference" "PL41"
			(at -0.829056 -16.776446 0)
			(unlocked yes)
			(layer "F.SilkS")
			(effects
				(font
					(size 0.7874 0.5842)
					(thickness 0.1524)
				)
				(justify left)
			)
		)
		(property "Value" ""
			(at 0 0 0)
			(layer "F.Fab")
			(effects
				(font
					(size 1.27 1.27)
				)
			)
		)
		(duplicate_pad_numbers_are_jumpers no)
		(fp_line
			(start -3.750056 -5.500116)
			(end -2.393442 -5.500116)
			(stroke
				(width 0.1524)
				(type default)
			)
			(layer "F.SilkS")
		)
		(fp_line
			(start -3.750056 5.500116)
			(end -3.750056 -5.500116)
			(stroke
				(width 0.1524)
				(type default)
			)
			(layer "F.SilkS")
		)
		(fp_line
			(start -2.393442 5.500116)
			(end -3.750056 5.500116)
			(stroke
				(width 0.1524)
				(type default)
			)
			(layer "F.SilkS")
		)
		(fp_line
			(start 2.393442 5.500116)
			(end 3.750056 5.500116)
			(stroke
				(width 0.1524)
				(type default)
			)
			(layer "F.SilkS")
		)
		(fp_line
			(start 3.750056 -5.500116)
			(end 2.393442 -5.500116)
			(stroke
				(width 0.1524)
				(type default)
			)
			(layer "F.SilkS")
		)
		(fp_line
			(start 3.750056 5.500116)
			(end 3.750056 -5.500116)
			(stroke
				(width 0.1524)
				(type default)
			)
			(layer "F.SilkS")
		)
		(fp_poly
			(pts
				(xy -3.9116 -4.249928) (xy -4.3434 -4.034028) (xy -4.3434 -4.465828)
			)
			(stroke
				(width 0)
				(type default)
			)
			(fill yes)
			(layer "F.SilkS")
		)
		(fp_line
			(start -3.750056 -5.500116)
			(end -3.750056 5.500116)
			(stroke
				(width 0.1)
				(type default)
			)
			(layer "F.Fab")
		)
		(fp_line
			(start -3.750056 5.500116)
			(end 3.750056 5.500116)
			(stroke
				(width 0.1)
				(type default)
			)
			(layer "F.Fab")
		)
		(fp_line
			(start 3.750056 -5.500116)
			(end -3.750056 -5.500116)
			(stroke
				(width 0.1)
				(type default)
			)
			(layer "F.Fab")
		)
		(fp_line
			(start 3.750056 5.500116)
			(end 3.750056 -5.500116)
			(stroke
				(width 0.1)
				(type default)
			)
			(layer "F.Fab")
		)
		(fp_poly
			(pts
				(xy -4.9276 -4.757928) (xy -4.9276 -3.741928) (xy -3.9116 -4.249928)
			)
			(stroke
				(width 0)
				(type default)
			)
			(fill yes)
			(layer "F.Fab")
		)
		(pad "1" smd rect
			(at 0 -4.249928 270)
			(size 2.413 4.5212)
			(layers "F.Cu" "F.Mask" "F.Paste")
			(net "SW_PVDDCR_CPU1_P1_SW2")
		)
		(pad "2" smd rect
			(at 0 -1.175004 270)
			(size 1.3716 4.5212)
			(layers "F.Cu" "F.Mask" "F.Paste")
			(net "IND_CPU1_P1_CPL1")
		)
		(pad "3" smd rect
			(at 0 1.175004 270)
			(size 1.3716 4.5212)
			(layers "F.Cu" "F.Mask" "F.Paste")
			(net "IND_CPU1_P1_CPL2")
		)
		(pad "4" smd rect
			(at 0 4.249928 270)
			(size 2.413 4.5212)
			(layers "F.Cu" "F.Mask" "F.Paste")
			(net "PVDDCR_CPU1_P1")
		)
	)
)
